(kicad_pcb
	(version 20260206)
	(generator "pcbnew")
	(generator_version "10.0")
	(general
		(thickness 1.6)
		(legacy_teardrops no)
	)
	(paper "A4")
	(title_block
		(title "v2-pdb — ms_pdb_v2.brd")
		(comment 1 "Open CloudServer (Microsoft) / footprint 293 of 348 (J26), pads 157-166 of 166")
	)
	(layers
		(0 "F.Cu" signal "TOP")
		(4 "In1.Cu" signal "GND")
		(6 "In2.Cu" signal "IN1")
		(8 "In3.Cu" signal "VCC")
		(10 "In4.Cu" signal "VCC1")
		(12 "In5.Cu" signal "IN2")
		(14 "In6.Cu" signal "GND1")
		(2 "B.Cu" signal "BOTTOM")
		(9 "F.Adhes" user "F.Adhesive")
		(11 "B.Adhes" user "B.Adhesive")
		(13 "F.Paste" user "Package Geometry/Pastemask Top")
		(15 "B.Paste" user "Package Geometry/Pastemask Bottom")
		(5 "F.SilkS" user "Ref Des/Silkscreen Top")
		(7 "B.SilkS" user "Ref Des/Silkscreen Bottom")
		(1 "F.Mask" user "Board Geometry/Soldermask Top")
		(3 "B.Mask" user "Board Geometry/Soldermask Bottom")
		(17 "Dwgs.User" user "User.Drawings")
		(19 "Cmts.User" user "User.Comments")
		(21 "Eco1.User" user "User.Eco1")
		(23 "Eco2.User" user "User.Eco2")
		(25 "Edge.Cuts" user "Board Geometry/Outline")
		(27 "Margin" user)
		(31 "F.CrtYd" user "Package Geometry/Place Bound Top")
		(29 "B.CrtYd" user "Package Geometry/Place Bound Bottom")
		(35 "F.Fab" user "Ref Des/Assembly Top")
		(33 "B.Fab" user "Ref Des/Assembly Bottom")
	)
	(footprint ""
		(layer "F.Cu")
		(at 6.448806 -261.670546)
		(property "Reference" "J26"
			(at 6.660642 8.995918 90)
			(unlocked yes)
			(layer "F.SilkS")
			(effects
				(font
					(size 0.7874 0.5842)
					(thickness 0.1524)
				)
				(justify left)
			)
		)
		(property "Value" ""
			(at 0 0 0)
			(layer "F.Fab")
			(effects
				(font
					(size 1.27 1.27)
				)
			)
		)
		(duplicate_pad_numbers_are_jumpers no)
		(pad "B73" thru_hole circle
			(at -2.499868 74.000106 270)
			(size 1.016 1.016)
			(drill 0.7112)
			(layers "*.Cu" "*.Mask")
			(remove_unused_layers no)
			(net "LAN1_P3_N")
			(clearance 0.1016)
			(thermal_gap 0.1016)
		)
		(pad "B74" thru_hole circle
			(at -4.499864 75.000104 270)
			(size 1.016 1.016)
			(drill 0.7112)
			(layers "*.Cu" "*.Mask")
			(remove_unused_layers no)
			(net "GND")
			(clearance 0.1016)
			(thermal_gap 0.1016)
		)
		(pad "B75" thru_hole circle
			(at -2.499868 76.000102 270)
			(size 1.016 1.016)
			(drill 0.7112)
			(layers "*.Cu" "*.Mask")
			(remove_unused_layers no)
			(net "LAN1_P4_P")
			(clearance 0.1016)
			(thermal_gap 0.1016)
		)
		(pad "B76" thru_hole circle
			(at -4.499864 77.0001 270)
			(size 1.016 1.016)
			(drill 0.7112)
			(layers "*.Cu" "*.Mask")
			(remove_unused_layers no)
			(net "LAN1_P4_N")
			(clearance 0.1016)
			(thermal_gap 0.1016)
		)
		(pad "B77" thru_hole circle
			(at -2.499868 78.000098 270)
			(size 1.016 1.016)
			(drill 0.7112)
			(layers "*.Cu" "*.Mask")
			(remove_unused_layers no)
			(net "GND")
			(clearance 0.1016)
			(thermal_gap 0.1016)
		)
		(pad "B78" thru_hole circle
			(at -4.499864 79.000096 270)
			(size 1.016 1.016)
			(drill 0.7112)
			(layers "*.Cu" "*.Mask")
			(remove_unused_layers no)
			(net "CM_PWR_CTL_IN")
			(clearance 0.1016)
			(thermal_gap 0.1016)
		)
		(pad "B79" thru_hole circle
			(at -2.499868 80.000094 270)
			(size 1.016 1.016)
			(drill 0.7112)
			(layers "*.Cu" "*.Mask")
			(remove_unused_layers no)
			(net "P12V")
			(clearance 0.1016)
			(thermal_gap 0.1016)
		)
		(pad "B80" thru_hole circle
			(at -4.499864 81.000092 270)
			(size 1.016 1.016)
			(drill 0.7112)
			(layers "*.Cu" "*.Mask")
			(remove_unused_layers no)
			(net "P12V")
			(clearance 0.1016)
			(thermal_gap 0.1016)
		)
		(pad "B81" thru_hole circle
			(at -2.499868 82.00009 270)
			(size 1.016 1.016)
			(drill 0.7112)
			(layers "*.Cu" "*.Mask")
			(remove_unused_layers no)
			(net "MATE_A1")
			(clearance 0.1016)
			(thermal_gap 0.1016)
		)
		(pad "B82" thru_hole circle
			(at -4.499864 83.000088 270)
			(size 1.016 1.016)
			(drill 0.7112)
			(layers "*.Cu" "*.Mask")
			(remove_unused_layers no)
			(net "P12V")
			(clearance 0.1016)
			(thermal_gap 0.1016)
		)
	)
)
